(kicad_pcb
	(version 20241229)
	(generator "pcbnew")
	(generator_version "9.0")
	(general
		(thickness 1.63)
		(legacy_teardrops no)
	)
	(paper "A4")
	(title_block
		(title "CM4 Baseboard")
		(date "2026-01-05")
		(rev "1.1.1")
		(company "Antmicro Ltd")
		(comment 1 "www.antmicro.com")
		(comment 9 "footprints 502-505 of 506")
	)
	(layers
		(0 "F.Cu" signal)
		(4 "In1.Cu" power)
		(6 "In2.Cu" power)
		(8 "In3.Cu" signal)
		(10 "In4.Cu" signal)
		(2 "B.Cu" signal)
		(9 "F.Adhes" user "F.Adhesive")
		(11 "B.Adhes" user "B.Adhesive")
		(13 "F.Paste" user)
		(15 "B.Paste" user)
		(5 "F.SilkS" user "F.Silkscreen")
		(7 "B.SilkS" user "B.Silkscreen")
		(1 "F.Mask" user)
		(3 "B.Mask" user)
		(17 "Dwgs.User" user "User.Drawings")
		(19 "Cmts.User" user "User.Comments")
		(21 "Eco1.User" user "User.Eco1")
		(23 "Eco2.User" user "User.Eco2")
		(25 "Edge.Cuts" user)
		(27 "Margin" user)
		(31 "F.CrtYd" user "F.Courtyard")
		(29 "B.CrtYd" user "B.Courtyard")
		(35 "F.Fab" user)
		(33 "B.Fab" user)
	)
	(footprint "antmicro-footprints:R_0402_1005Metric"
		(layer "B.Cu")
		(at 76.142962 126.6165 180)
		(descr "Resistor SMD 0402")
		(tags "resistor SMD 0402")
		(property "Reference" "R904"
			(at -0.935 0.58 0)
			(layer "B.SilkS")
			(effects
				(font
					(size 0.7 0.7)
					(thickness 0.15)
				)
				(justify left bottom mirror)
			)
		)
		(property "Value" "R_100k_0402"
			(at -1.011843 -1.772047 0)
			(layer "B.Fab")
			(effects
				(font
					(size 0.7 0.7)
					(thickness 0.15)
				)
				(justify left bottom mirror)
			)
		)
		(property "Datasheet" "https://www.bourns.com/docs/product-datasheets/cr.pdf"
			(at 0 0 180)
			(layer "B.Fab")
			(hide yes)
			(effects
				(font
					(size 1.27 1.27)
					(thickness 0.15)
				)
			)
		)
		(property "Manufacturer" "Bourns"
			(at 0 0 180)
			(unlocked yes)
			(layer "B.Fab")
			(hide yes)
			(effects
				(font
					(size 1 1)
					(thickness 0.15)
				)
				(justify mirror)
			)
		)
		(property "MPN" "CR0402-FX-1003GLF"
			(at 0 0 180)
			(unlocked yes)
			(layer "B.Fab")
			(hide yes)
			(effects
				(font
					(size 1 1)
					(thickness 0.15)
				)
				(justify mirror)
			)
		)
		(property "Val" "100k"
			(at 0 0 180)
			(unlocked yes)
			(layer "B.Fab")
			(hide yes)
			(effects
				(font
					(size 1 1)
					(thickness 0.15)
				)
				(justify mirror)
			)
		)
		(property "License" "Apache-2.0"
			(at 0 0 180)
			(unlocked yes)
			(layer "B.Fab")
			(hide yes)
			(effects
				(font
					(size 1 1)
					(thickness 0.15)
				)
				(justify mirror)
			)
		)
		(property "Author" "Antmicro"
			(at 0 0 180)
			(unlocked yes)
			(layer "B.Fab")
			(hide yes)
			(effects
				(font
					(size 1 1)
					(thickness 0.15)
				)
				(justify mirror)
			)
		)
		(property "Tolerance" "1%"
			(at 0 0 180)
			(unlocked yes)
			(layer "B.Fab")
			(hide yes)
			(effects
				(font
					(size 1 1)
					(thickness 0.15)
				)
				(justify mirror)
			)
		)
		(sheetname "/USB/")
		(sheetfile "usb.kicad_sch")
		(attr smd)
		(fp_rect
			(start -0.925 0.47)
			(end 0.925 -0.47)
			(stroke
				(width 0.05)
				(type default)
			)
			(fill no)
			(layer "B.CrtYd")
		)
		(fp_rect
			(start -0.5 0.25)
			(end 0.5 -0.25)
			(stroke
				(width 0.15)
				(type solid)
			)
			(fill no)
			(layer "B.Fab")
		)
		(fp_text user "License: Apache-2.0"
			(at -0.95 -5.169 0)
			(layer "B.Fab")
			(effects
				(font
					(size 0.7 0.7)
					(thickness 0.15)
				)
				(justify left bottom mirror)
			)
		)
		(fp_text user "${REFERENCE}"
			(at -0.95 -3.168 0)
			(layer "B.Fab")
			(effects
				(font
					(size 0.7 0.7)
					(thickness 0.15)
				)
				(justify left bottom mirror)
			)
		)
		(fp_text user "Author: Antmicro"
			(at -0.95 -4.169 0)
			(layer "B.Fab")
			(effects
				(font
					(size 0.7 0.7)
					(thickness 0.15)
				)
				(justify left bottom mirror)
			)
		)
		(pad "1" smd roundrect
			(at -0.48 0 180)
			(size 0.59 0.64)
			(layers "B.Cu" "B.Mask" "B.Paste")
			(roundrect_rratio 0.25)
			(net 26 "/USB/USBD_VBUS")
			(pintype "passive")
		)
		(pad "2" smd roundrect
			(at 0.48 0 180)
			(size 0.59 0.64)
			(layers "B.Cu" "B.Mask" "B.Paste")
			(roundrect_rratio 0.25)
			(net 341 "Net-(Q902-G)")
			(pintype "passive")
		)
	)
	(footprint "antmicro-footprints:R_0402_1005Metric"
		(layer "B.Cu")
		(at 51.542962 136.1165)
		(descr "Resistor SMD 0402")
		(tags "resistor SMD 0402")
		(property "Reference" "R418"
			(at -1.965 1.37 0)
			(layer "B.SilkS")
			(effects
				(font
					(size 0.7 0.7)
					(thickness 0.15)
				)
				(justify right bottom mirror)
			)
		)
		(property "Value" "R_470R_0402"
			(at -1.011843 -1.772047 0)
			(layer "B.Fab")
			(effects
				(font
					(size 0.7 0.7)
					(thickness 0.15)
				)
				(justify right bottom mirror)
			)
		)
		(property "Datasheet" "https://www.bourns.com/docs/product-datasheets/cr.pdf"
			(at 0 0 0)
			(layer "B.Fab")
			(hide yes)
			(effects
				(font
					(size 1.27 1.27)
					(thickness 0.15)
				)
			)
		)
		(property "Manufacturer" "Bourns"
			(at 0 0 0)
			(unlocked yes)
			(layer "B.Fab")
			(hide yes)
			(effects
				(font
					(size 1 1)
					(thickness 0.15)
				)
				(justify mirror)
			)
		)
		(property "MPN" "CR0402-FX-4700GLF"
			(at 0 0 0)
			(unlocked yes)
			(layer "B.Fab")
			(hide yes)
			(effects
				(font
					(size 1 1)
					(thickness 0.15)
				)
				(justify mirror)
			)
		)
		(property "Val" "470R"
			(at 0 0 0)
			(unlocked yes)
			(layer "B.Fab")
			(hide yes)
			(effects
				(font
					(size 1 1)
					(thickness 0.15)
				)
				(justify mirror)
			)
		)
		(property "License" "Apache-2.0"
			(at 0 0 0)
			(unlocked yes)
			(layer "B.Fab")
			(hide yes)
			(effects
				(font
					(size 1 1)
					(thickness 0.15)
				)
				(justify mirror)
			)
		)
		(property "Author" "Antmicro"
			(at 0 0 0)
			(unlocked yes)
			(layer "B.Fab")
			(hide yes)
			(effects
				(font
					(size 1 1)
					(thickness 0.15)
				)
				(justify mirror)
			)
		)
		(property "Tolerance" "1%"
			(at 0 0 0)
			(unlocked yes)
			(layer "B.Fab")
			(hide yes)
			(effects
				(font
					(size 1 1)
					(thickness 0.15)
				)
				(justify mirror)
			)
		)
		(sheetname "/Ethernet/")
		(sheetfile "ethernet.kicad_sch")
		(attr smd)
		(fp_rect
			(start -0.925 0.47)
			(end 0.925 -0.47)
			(stroke
				(width 0.05)
				(type default)
			)
			(fill no)
			(layer "B.CrtYd")
		)
		(fp_rect
			(start -0.5 0.25)
			(end 0.5 -0.25)
			(stroke
				(width 0.15)
				(type solid)
			)
			(fill no)
			(layer "B.Fab")
		)
		(fp_text user "License: Apache-2.0"
			(at -0.95 -5.169 180)
			(layer "B.Fab")
			(effects
				(font
					(size 0.7 0.7)
					(thickness 0.15)
				)
				(justify left bottom mirror)
			)
		)
		(fp_text user "${REFERENCE}"
			(at -0.95 -3.168 180)
			(layer "B.Fab")
			(effects
				(font
					(size 0.7 0.7)
					(thickness 0.15)
				)
				(justify left bottom mirror)
			)
		)
		(fp_text user "Author: Antmicro"
			(at -0.95 -4.169 180)
			(layer "B.Fab")
			(effects
				(font
					(size 0.7 0.7)
					(thickness 0.15)
				)
				(justify left bottom mirror)
			)
		)
		(pad "1" smd roundrect
			(at -0.48 0)
			(size 0.59 0.64)
			(layers "B.Cu" "B.Mask" "B.Paste")
			(roundrect_rratio 0.25)
			(net 1 "GNDD")
			(pintype "passive")
		)
		(pad "2" smd roundrect
			(at 0.48 0)
			(size 0.59 0.64)
			(layers "B.Cu" "B.Mask" "B.Paste")
			(roundrect_rratio 0.25)
			(net 366 "Net-(R418-Pad2)")
			(pintype "passive")
		)
	)
	(footprint "antmicro-footprints:R_0402_1005Metric"
		(layer "B.Cu")
		(at 86.842962 123.1415)
		(descr "Resistor SMD 0402")
		(tags "resistor SMD 0402")
		(property "Reference" "R910"
			(at 0.955 -0.565 0)
			(layer "B.SilkS")
			(effects
				(font
					(size 0.7 0.7)
					(thickness 0.15)
				)
				(justify right bottom mirror)
			)
		)
		(property "Value" "R_10k_0402"
			(at -1.011843 -1.772047 0)
			(layer "B.Fab")
			(effects
				(font
					(size 0.7 0.7)
					(thickness 0.15)
				)
				(justify right bottom mirror)
			)
		)
		(property "Datasheet" "https://www.bourns.com/docs/product-datasheets/cr.pdf"
			(at 0 0 0)
			(layer "B.Fab")
			(hide yes)
			(effects
				(font
					(size 1.27 1.27)
					(thickness 0.15)
				)
			)
		)
		(property "Manufacturer" "Bourns"
			(at 0 0 0)
			(unlocked yes)
			(layer "B.Fab")
			(hide yes)
			(effects
				(font
					(size 1 1)
					(thickness 0.15)
				)
				(justify mirror)
			)
		)
		(property "MPN" "CR0402-FX-1002GLF"
			(at 0 0 0)
			(unlocked yes)
			(layer "B.Fab")
			(hide yes)
			(effects
				(font
					(size 1 1)
					(thickness 0.15)
				)
				(justify mirror)
			)
		)
		(property "Val" "10k"
			(at 0 0 0)
			(unlocked yes)
			(layer "B.Fab")
			(hide yes)
			(effects
				(font
					(size 1 1)
					(thickness 0.15)
				)
				(justify mirror)
			)
		)
		(property "License" "Apache-2.0"
			(at 0 0 0)
			(unlocked yes)
			(layer "B.Fab")
			(hide yes)
			(effects
				(font
					(size 1 1)
					(thickness 0.15)
				)
				(justify mirror)
			)
		)
		(property "Author" "Antmicro"
			(at 0 0 0)
			(unlocked yes)
			(layer "B.Fab")
			(hide yes)
			(effects
				(font
					(size 1 1)
					(thickness 0.15)
				)
				(justify mirror)
			)
		)
		(property "Tolerance" "1%"
			(at 0 0 0)
			(unlocked yes)
			(layer "B.Fab")
			(hide yes)
			(effects
				(font
					(size 1 1)
					(thickness 0.15)
				)
				(justify mirror)
			)
		)
		(sheetname "/USB/")
		(sheetfile "usb.kicad_sch")
		(attr smd)
		(fp_rect
			(start -0.925 0.47)
			(end 0.925 -0.47)
			(stroke
				(width 0.05)
				(type default)
			)
			(fill no)
			(layer "B.CrtYd")
		)
		(fp_rect
			(start -0.5 0.25)
			(end 0.5 -0.25)
			(stroke
				(width 0.15)
				(type solid)
			)
			(fill no)
			(layer "B.Fab")
		)
		(fp_text user "${REFERENCE}"
			(at -0.95 -3.168 180)
			(layer "B.Fab")
			(effects
				(font
					(size 0.7 0.7)
					(thickness 0.15)
				)
				(justify left bottom mirror)
			)
		)
		(fp_text user "Author: Antmicro"
			(at -0.95 -4.169 180)
			(layer "B.Fab")
			(effects
				(font
					(size 0.7 0.7)
					(thickness 0.15)
				)
				(justify left bottom mirror)
			)
		)
		(fp_text user "License: Apache-2.0"
			(at -0.95 -5.169 180)
			(layer "B.Fab")
			(effects
				(font
					(size 0.7 0.7)
					(thickness 0.15)
				)
				(justify left bottom mirror)
			)
		)
		(pad "1" smd roundrect
			(at -0.48 0)
			(size 0.59 0.64)
			(layers "B.Cu" "B.Mask" "B.Paste")
			(roundrect_rratio 0.25)
			(net 3 "GND")
			(pintype "passive")
		)
		(pad "2" smd roundrect
			(at 0.48 0)
			(size 0.59 0.64)
			(layers "B.Cu" "B.Mask" "B.Paste")
			(roundrect_rratio 0.25)
			(net 343 "/USB/EN_FTDI")
			(pintype "passive")
		)
	)
	(footprint "antmicro-footprints:Nexperia_DFN-10_2.5x1mm_P0.5mm"
		(layer "B.Cu")
		(at 101.080962 169.8785 90)
		(property "Reference" "D705"
			(at -0.608 2.597 90)
			(layer "B.SilkS")
			(effects
				(font
					(size 0.7 0.7)
					(thickness 0.15)
				)
				(justify right bottom mirror)
			)
		)
		(property "Value" "PUSB3F96X_PASS"
			(at -0.016 -1.705 90)
			(layer "B.Fab")
			(effects
				(font
					(size 0.7 0.7)
					(thickness 0.15)
				)
				(justify right bottom mirror)
			)
		)
		(property "Datasheet" "https://mouser.com/datasheet/2/916/PUSB3F96-1600324.pdf"
			(at 0 0 90)
			(layer "B.Fab")
			(hide yes)
			(effects
				(font
					(size 1.27 1.27)
					(thickness 0.15)
				)
			)
		)
		(property "Manufacturer" "Nexperia"
			(at 0 0 90)
			(unlocked yes)
			(layer "B.Fab")
			(hide yes)
			(effects
				(font
					(size 1 1)
					(thickness 0.15)
				)
				(justify mirror)
			)
		)
		(property "MPN" "PUSB3F96X"
			(at 0 0 90)
			(unlocked yes)
			(layer "B.Fab")
			(hide yes)
			(effects
				(font
					(size 1 1)
					(thickness 0.15)
				)
				(justify mirror)
			)
		)
		(property "Author" "Antmicro"
			(at 0 0 90)
			(unlocked yes)
			(layer "B.Fab")
			(hide yes)
			(effects
				(font
					(size 1 1)
					(thickness 0.15)
				)
				(justify mirror)
			)
		)
		(property "License" "Apache-2.0"
			(at 0 0 90)
			(unlocked yes)
			(layer "B.Fab")
			(hide yes)
			(effects
				(font
					(size 1 1)
					(thickness 0.15)
				)
				(justify mirror)
			)
		)
		(sheetname "/Display/")
		(sheetfile "display.kicad_sch")
		(attr smd)
		(fp_line
			(start 1.375 -0.4)
			(end 1.375 0.4)
			(stroke
				(width 0.15)
				(type solid)
			)
			(layer "B.SilkS")
		)
		(fp_line
			(start -1.375 0.4)
			(end -1.375 -0.4)
			(stroke
				(width 0.15)
				(type solid)
			)
			(layer "B.SilkS")
		)
		(fp_circle
			(center -1.4 -0.7)
			(end -1.349 -0.7)
			(stroke
				(width 0.15)
				(type solid)
			)
			(fill yes)
			(layer "B.SilkS")
		)
		(fp_rect
			(start -1.4 0.725)
			(end 1.4 -0.725)
			(stroke
				(width 0.05)
				(type solid)
			)
			(fill no)
			(layer "B.CrtYd")
		)
		(fp_line
			(start 1.25 -0.5)
			(end 1.25 0.5)
			(stroke
				(width 0.15)
				(type solid)
			)
			(layer "B.Fab")
		)
		(fp_line
			(start -0.9 -0.5)
			(end 1.25 -0.5)
			(stroke
				(width 0.15)
				(type solid)
			)
			(layer "B.Fab")
		)
		(fp_line
			(start -1.25 -0.15)
			(end -0.9 -0.5)
			(stroke
				(width 0.15)
				(type solid)
			)
			(layer "B.Fab")
		)
		(fp_line
			(start 1.25 0.5)
			(end -1.25 0.5)
			(stroke
				(width 0.15)
				(type solid)
			)
			(layer "B.Fab")
		)
		(fp_line
			(start -1.25 0.5)
			(end -1.25 -0.15)
			(stroke
				(width 0.15)
				(type solid)
			)
			(layer "B.Fab")
		)
		(fp_text user "Author: Antmicro"
			(at -1.367 -4.905 270)
			(layer "B.Fab")
			(effects
				(font
					(size 0.7 0.7)
					(thickness 0.15)
				)
				(justify left bottom mirror)
			)
		)
		(fp_text user "${REFERENCE}"
			(at -1.367 -3.704 270)
			(layer "B.Fab")
			(effects
				(font
					(size 0.7 0.7)
					(thickness 0.15)
				)
				(justify left bottom mirror)
			)
		)
		(fp_text user "License: Apache-2.0"
			(at -1.367 -6.105 270)
			(layer "B.Fab")
			(effects
				(font
					(size 0.7 0.7)
					(thickness 0.15)
				)
				(justify left bottom mirror)
			)
		)
		(pad "1" smd rect
			(at -1 -0.3875 90)
			(size 0.2 0.475)
			(layers "B.Cu" "B.Mask" "B.Paste")
			(net 122 "/Compute module/DSICtrl.EN")
			(pinfunction "CH1")
			(pintype "passive")
			(solder_mask_margin 0.05)
		)
		(pad "2" smd rect
			(at -0.5 -0.3875 90)
			(size 0.2 0.475)
			(layers "B.Cu" "B.Mask" "B.Paste")
			(net 123 "/Compute module/DSICtrl.~{RST}")
			(pinfunction "CH2")
			(pintype "passive")
			(solder_mask_margin 0.05)
		)
		(pad "3" smd rect
			(at 0 -0.3875 90)
			(size 0.2 0.475)
			(layers "B.Cu" "B.Mask" "B.Paste")
			(net 3 "GND")
			(pinfunction "GND")
			(pintype "passive")
			(solder_mask_margin 0.05)
		)
		(pad "4" smd rect
			(at 0.5 -0.3875 90)
			(size 0.2 0.475)
			(layers "B.Cu" "B.Mask" "B.Paste")
			(net 124 "/Compute module/DSICtrl.DIM")
			(pinfunction "CH3")
			(pintype "passive")
			(solder_mask_margin 0.05)
		)
		(pad "5" smd rect
			(at 1 -0.3875 90)
			(size 0.2 0.475)
			(layers "B.Cu" "B.Mask" "B.Paste")
			(net 125 "/Compute module/DSICtrl.GPIO")
			(pinfunction "CH4")
			(pintype "passive")
			(solder_mask_margin 0.05)
		)
		(pad "6" smd rect
			(at 1 0.3875 90)
			(size 0.2 0.475)
			(layers "B.Cu" "B.Mask" "B.Paste")
			(net 125 "/Compute module/DSICtrl.GPIO")
			(pinfunction "CH4")
			(pintype "passive")
			(solder_mask_margin 0.05)
		)
		(pad "7" smd rect
			(at 0.5 0.3875 90)
			(size 0.2 0.475)
			(layers "B.Cu" "B.Mask" "B.Paste")
			(net 124 "/Compute module/DSICtrl.DIM")
			(pinfunction "CH3")
			(pintype "passive")
			(solder_mask_margin 0.05)
		)
		(pad "8" smd rect
			(at 0 0.3875 90)
			(size 0.2 0.475)
			(layers "B.Cu" "B.Mask" "B.Paste")
			(net 3 "GND")
			(pinfunction "GND")
			(pintype "passive")
			(solder_mask_margin 0.05)
		)
		(pad "9" smd rect
			(at -0.501 0.3875 90)
			(size 0.2 0.475)
			(layers "B.Cu" "B.Mask" "B.Paste")
			(net 123 "/Compute module/DSICtrl.~{RST}")
			(pinfunction "CH2")
			(pintype "passive")
			(solder_mask_margin 0.05)
		)
		(pad "10" smd rect
			(at -1 0.3875 90)
			(size 0.2 0.475)
			(layers "B.Cu" "B.Mask" "B.Paste")
			(net 122 "/Compute module/DSICtrl.EN")
			(pinfunction "CH1")
			(pintype "passive")
			(solder_mask_margin 0.05)
		)
	)
)
